# LED Board_Stackup.xlsx — 工作表2 (pcb-stackup)
|  |  |  |  |  |  | Version |  |  |  |  |  |  |  |
| Board Number: |  | 16368-SB |  |  |  | 01 |  |  |  |  |  |  |  |
| Project name: |  | Leopard_BW_Channel |  |  |  |  |  |  |  |  |  |  |  |
| Model Name: |  | LED Board |  |  |  |  |  |  |  |  |  |  |  |
| Layer Count: |  | 6 Layer |  |  |  |  |  |  |  |  |  |  |  |
| Date: |  | 2017-01-20 00:00:00 |  |  |  |  |  |  |  |  |  |  |  |
| Material: |  | TU747HF / IT150G / NPG150N |  |  |  |  |  |  |  | Single Ended Type(mil) |  |  |  |
| Gold Finger(Y/N) |  | N |  |  |  |  |  |  | Imp | 50 |  |  |  |
| Customer: |  | XXXXX |  |  |  |  |  |  | Variation | Inner/Outer+/-5ohm |  |  |  |
| EE engineer |  | <name> |  |  |  |  |  |  | Bus | MISC. |  |  |  |
| SI Engineer |  | <name> |  |  |  |  |  |  |  |  |  |  |  |
|  |  |  |  |  |  |  |  |  | Type | SE |  |  |  |
| Layer |  |  | Thickness |  | Glass/Copper Style | Er |  | Df(1G) | Layers | 1,3,4,6 |  |  |  |
|  |  | Cu oz | Wiwynn |  |  | Wiwynn |  |  |  | Wiwynn |  |  |  |
|  | Mask |  | 0.5 |  |  | 3.4 |  |  |  | Width | Imp | Width | Imp |
| Top | Signal | 0.5 oz+plating | 1.9 |  |  |  |  |  | S1 | 7(L2) |  |  |  |
|  | Prepreg |  | 4 |  |  | 4 |  |  |  |  |  |  |  |
| L2 | GND | 1 oz | 1.3 |  |  |  |  |  | P2 | reference layer |  |  |  |
|  | Core |  | 4 |  |  | 4 |  |  |  |  |  |  |  |
| L3 | Signal | 1 oz | 1.3 |  |  |  |  |  | S3 | 5(L2/L5) |  |  |  |
|  | Prepreg |  | 36 |  |  | 4.5 |  |  |  |  |  |  |  |
| L4 | Signal | 1 oz | 1.3 | 0 | 0 |  |  |  | S4 | 5(L2/L5) |  |  |  |
|  | Core |  | 4 | 0 | 0 | 4 | 0 | 0 |  |  |  |  |  |
| L5 | GND | 1 oz | 1.3 | 0 | 0 |  |  |  | P5 | reference layer |  |  |  |
|  | Prepreg |  | 4 | 0 | 0 | 4 | 0 | 0 |  |  |  |  |  |
| Bottom | Signal | 0.5 oz+plating | 1.9 | 0 | 0 |  |  |  | S6 | 7(L5) |  |  |  |
|  | Mask |  | 0.5 | 0 |  | 3.4 | 0 | 0 |  |  |  |  |  |
| Thickness requirement: 1.57 ± 10% mm |  | mil | 61.99999999999999 |  |  |  |  |  |  |  |  |  |  |
|  |  | mm | 1.574803149606299 |  |  |  |  |  |  |  |  |  |  |
| Note: | 1. Unit is mil |  |  |  |  |  |  |  |  |  |  |  |  |
|  | 2. The total thickness includes trace and solder mask |  |  |  |  |  |  |  |  |  |  |  |  |
|  | 3. Min hole copper thickness is 1.0 mil |  |  |  |  |  |  |  |  |  |  |  |  |
|  | 4. Min surface copper thickness 1.5 mil |  |  |  |  |  |  |  |  |  |  |  |  |
|  | 5. Impedance Cpk requirement: >=1.33 (Report should be provided) |  |  |  |  |  |  |  |  |  |  |  |  |
|  | 6. PCB supplier should design SET2DIL coupon and provide measurement results meeting following criteria: |  |  |  |  |  |  |  |  |  |  |  |  |
|  | 。  -0.75dB/inch at 4GHz for stripline routing |  |  |  |  |  |  |  |  |  |  |  |  |
|  | 。  -0.79dB/inch at 4GHz for microstrip routing |  |  |  |  |  |  |  |  |  |  |  |  |
